(kicad_pcb
	(version 20260206)
	(generator "pcbnew")
	(generator_version "10.0")
	(general
		(thickness 1.6)
		(legacy_teardrops no)
	)
	(paper "A4")
	(title_block
		(title "v1-chassis-manager — T6M_CM_d_v01_1031_1645.brd")
		(comment 1 "Open CloudServer (Microsoft) / footprints 395-404 of 2512")
	)
	(layers
		(0 "F.Cu" signal "TOP")
		(4 "In1.Cu" signal "GND1")
		(6 "In2.Cu" signal "IN1")
		(8 "In3.Cu" signal "VCC1")
		(10 "In4.Cu" signal "VCC2")
		(12 "In5.Cu" signal "GND2")
		(14 "In6.Cu" signal "IN2")
		(16 "In7.Cu" signal "IN3")
		(18 "In8.Cu" signal "GND3")
		(2 "B.Cu" signal "BOTTOM")
		(9 "F.Adhes" user "F.Adhesive")
		(11 "B.Adhes" user "B.Adhesive")
		(13 "F.Paste" user "Package Geometry/Pastemask Top")
		(15 "B.Paste" user "Package Geometry/Pastemask Bottom")
		(5 "F.SilkS" user "Ref Des/Silkscreen Top")
		(7 "B.SilkS" user "Ref Des/Silkscreen Bottom")
		(1 "F.Mask" user "Board Geometry/Soldermask Top")
		(3 "B.Mask" user "Board Geometry/Soldermask Bottom")
		(17 "Dwgs.User" user "User.Drawings")
		(19 "Cmts.User" user "User.Comments")
		(21 "Eco1.User" user "User.Eco1")
		(23 "Eco2.User" user "User.Eco2")
		(25 "Edge.Cuts" user "Board Geometry/Outline")
		(27 "Margin" user)
		(31 "F.CrtYd" user "Package Geometry/Place Bound Top")
		(29 "B.CrtYd" user "Package Geometry/Place Bound Bottom")
		(35 "F.Fab" user "Ref Des/Assembly Top")
		(33 "B.Fab" user "Ref Des/Assembly Bottom")
	)
	(footprint ""
		(layer "F.Cu")
		(at 119.444262 -156.94152)
		(property "Reference" "C934"
			(at -0.785622 -1.895602 0)
			(unlocked yes)
			(layer "F.SilkS")
			(effects
				(font
					(size 0.635 0.4064)
					(thickness 0.1524)
				)
			)
		)
		(property "Value" ""
			(at 0 0 0)
			(layer "F.Fab")
			(effects
				(font
					(size 1.27 1.27)
				)
			)
		)
		(duplicate_pad_numbers_are_jumpers no)
		(fp_line
			(start -1.2954 -0.5842)
			(end 1.2954 -0.5842)
			(stroke
				(width 0.1524)
				(type default)
			)
			(layer "F.SilkS")
		)
		(fp_line
			(start -1.2954 0.5842)
			(end -1.2954 -0.5842)
			(stroke
				(width 0.1524)
				(type default)
			)
			(layer "F.SilkS")
		)
		(fp_line
			(start 0 -0.5842)
			(end 0 0.5842)
			(stroke
				(width 0.1524)
				(type default)
			)
			(layer "F.SilkS")
		)
		(fp_line
			(start 1.2954 -0.5842)
			(end 1.2954 0.5842)
			(stroke
				(width 0.1524)
				(type default)
			)
			(layer "F.SilkS")
		)
		(fp_line
			(start 1.2954 0.5842)
			(end -1.2954 0.5842)
			(stroke
				(width 0.1524)
				(type default)
			)
			(layer "F.SilkS")
		)
		(fp_poly
			(pts
				(xy 0.8636 -0.4572) (xy 0.8636 -0.3556) (xy 1.143 -0.3556) (xy 1.143 0.3556) (xy 0.8636 0.3556)
				(xy 0.8636 0.4572) (xy -0.8636 0.4572) (xy -0.8636 0.3556) (xy -1.143 0.3556) (xy -1.143 -0.3556)
				(xy -0.8636 -0.3556) (xy -0.8636 -0.4572)
			)
			(stroke
				(width 0)
				(type default)
			)
			(fill no)
			(layer "F.CrtYd")
		)
		(fp_line
			(start -0.884936 -0.504952)
			(end 0.884936 -0.504952)
			(stroke
				(width 0.1)
				(type default)
			)
			(layer "F.Fab")
		)
		(fp_line
			(start -0.884936 0.504952)
			(end -0.884936 -0.504952)
			(stroke
				(width 0.1)
				(type default)
			)
			(layer "F.Fab")
		)
		(fp_line
			(start 0.884936 -0.504952)
			(end 0.884936 0.504952)
			(stroke
				(width 0.1)
				(type default)
			)
			(layer "F.Fab")
		)
		(fp_line
			(start 0.884936 0.504952)
			(end -0.884936 0.504952)
			(stroke
				(width 0.1)
				(type default)
			)
			(layer "F.Fab")
		)
		(pad "1" smd rect
			(at 0.7366 0 90)
			(size 0.7112 0.8128)
			(layers "F.Cu" "F.Mask" "F.Paste")
			(net "GND")
		)
		(pad "2" smd rect
			(at -0.7366 0 90)
			(size 0.7112 0.8128)
			(layers "F.Cu" "F.Mask" "F.Paste")
			(net "N52998261")
		)
	)
	(footprint ""
		(layer "F.Cu")
		(at 159.62376 -185.205624 -90)
		(property "Reference" "R819"
			(at -4.768088 -0.272288 90)
			(unlocked yes)
			(layer "F.SilkS")
			(effects
				(font
					(size 0.7874 0.5842)
					(thickness 0.1524)
				)
				(justify left)
			)
		)
		(property "Value" ""
			(at 0 0 270)
			(layer "F.Fab")
			(effects
				(font
					(size 1.27 1.27)
				)
			)
		)
		(duplicate_pad_numbers_are_jumpers no)
		(fp_line
			(start -0.7874 0.4064)
			(end -0.7874 -0.4064)
			(stroke
				(width 0.1524)
				(type default)
			)
			(layer "F.SilkS")
		)
		(fp_line
			(start 0.7874 0.4064)
			(end -0.7874 0.4064)
			(stroke
				(width 0.1524)
				(type default)
			)
			(layer "F.SilkS")
		)
		(fp_line
			(start -0.7874 -0.4064)
			(end 0.7874 -0.4064)
			(stroke
				(width 0.1524)
				(type default)
			)
			(layer "F.SilkS")
		)
		(fp_line
			(start 0.7874 -0.4064)
			(end 0.7874 0.4064)
			(stroke
				(width 0.1524)
				(type default)
			)
			(layer "F.SilkS")
		)
		(fp_poly
			(pts
				(xy -0.508 0.2794) (xy -0.508 0.2286) (xy -0.635 0.2286) (xy -0.635 -0.254) (xy -0.5334 -0.254)
				(xy -0.5334 -0.2794) (xy 0.5334 -0.2794) (xy 0.5334 -0.254) (xy 0.635 -0.254) (xy 0.635 0.254) (xy 0.5334 0.254)
				(xy 0.5334 0.2794)
			)
			(stroke
				(width 0)
				(type default)
			)
			(fill no)
			(layer "F.CrtYd")
		)
		(pad "1" smd rect
			(at 0.40005 0 270)
			(size 0.4572 0.508)
			(layers "F.Cu" "F.Mask" "F.Paste")
			(net "FAN_PWM")
		)
		(pad "2" smd rect
			(at -0.40005 0 270)
			(size 0.4572 0.508)
			(layers "F.Cu" "F.Mask" "F.Paste")
			(net "FAN_PWM_R")
		)
	)
	(footprint ""
		(layer "F.Cu")
		(at 98.161856 -162.227768 -90)
		(property "Reference" "R655"
			(at 73.441814 -87.743792 90)
			(unlocked yes)
			(layer "F.SilkS")
			(effects
				(font
					(size 0.7874 0.5842)
					(thickness 0.1524)
				)
				(justify left)
			)
		)
		(property "Value" ""
			(at 0 0 270)
			(layer "F.Fab")
			(effects
				(font
					(size 1.27 1.27)
				)
			)
		)
		(duplicate_pad_numbers_are_jumpers no)
		(fp_line
			(start -0.7874 0.4064)
			(end -0.7874 -0.4064)
			(stroke
				(width 0.1524)
				(type default)
			)
			(layer "F.SilkS")
		)
		(fp_line
			(start 0.7874 0.4064)
			(end -0.7874 0.4064)
			(stroke
				(width 0.1524)
				(type default)
			)
			(layer "F.SilkS")
		)
		(fp_line
			(start -0.7874 -0.4064)
			(end 0.7874 -0.4064)
			(stroke
				(width 0.1524)
				(type default)
			)
			(layer "F.SilkS")
		)
		(fp_line
			(start 0.7874 -0.4064)
			(end 0.7874 0.4064)
			(stroke
				(width 0.1524)
				(type default)
			)
			(layer "F.SilkS")
		)
		(fp_poly
			(pts
				(xy -0.508 0.2794) (xy -0.508 0.2286) (xy -0.635 0.2286) (xy -0.635 -0.254) (xy -0.5334 -0.254)
				(xy -0.5334 -0.2794) (xy 0.5334 -0.2794) (xy 0.5334 -0.254) (xy 0.635 -0.254) (xy 0.635 0.254) (xy 0.5334 0.254)
				(xy 0.5334 0.2794)
			)
			(stroke
				(width 0)
				(type default)
			)
			(fill no)
			(layer "F.CrtYd")
		)
		(pad "1" smd rect
			(at 0.40005 0 270)
			(size 0.4572 0.508)
			(layers "F.Cu" "F.Mask" "F.Paste")
			(net "N52411040")
		)
		(pad "2" smd rect
			(at -0.40005 0 270)
			(size 0.4572 0.508)
			(layers "F.Cu" "F.Mask" "F.Paste")
			(net "P12V_AUX")
		)
	)
	(footprint ""
		(layer "F.Cu")
		(at 102.016306 -134.11581 180)
		(property "Reference" "PR46"
			(at 4.393692 8.411972 0)
			(unlocked yes)
			(layer "F.SilkS")
			(effects
				(font
					(size 0.7874 0.5842)
					(thickness 0.1524)
				)
				(justify left)
			)
		)
		(property "Value" ""
			(at 0 0 180)
			(layer "F.Fab")
			(effects
				(font
					(size 1.27 1.27)
				)
			)
		)
		(duplicate_pad_numbers_are_jumpers no)
		(fp_line
			(start 0.7874 0.4064)
			(end -0.7874 0.4064)
			(stroke
				(width 0.1524)
				(type default)
			)
			(layer "F.SilkS")
		)
		(fp_line
			(start 0.7874 -0.4064)
			(end 0.7874 0.4064)
			(stroke
				(width 0.1524)
				(type default)
			)
			(layer "F.SilkS")
		)
		(fp_line
			(start -0.7874 0.4064)
			(end -0.7874 -0.4064)
			(stroke
				(width 0.1524)
				(type default)
			)
			(layer "F.SilkS")
		)
		(fp_line
			(start -0.7874 -0.4064)
			(end 0.7874 -0.4064)
			(stroke
				(width 0.1524)
				(type default)
			)
			(layer "F.SilkS")
		)
		(fp_poly
			(pts
				(xy -0.508 0.2794) (xy -0.508 0.2286) (xy -0.635 0.2286) (xy -0.635 -0.254) (xy -0.5334 -0.254)
				(xy -0.5334 -0.2794) (xy 0.5334 -0.2794) (xy 0.5334 -0.254) (xy 0.635 -0.254) (xy 0.635 0.254) (xy 0.5334 0.254)
				(xy 0.5334 0.2794)
			)
			(stroke
				(width 0)
				(type default)
			)
			(fill no)
			(layer "F.CrtYd")
		)
		(pad "1" smd rect
			(at 0.40005 0 180)
			(size 0.4572 0.508)
			(layers "F.Cu" "F.Mask" "F.Paste")
			(net "SVID_CPU_NODE1_PVCCP_DAT")
		)
		(pad "2" smd rect
			(at -0.40005 0 180)
			(size 0.4572 0.508)
			(layers "F.Cu" "F.Mask" "F.Paste")
			(net "SVID_CPU_NODE1_DAT_R")
		)
	)
	(footprint ""
		(layer "F.Cu")
		(at 125.800104 -50.070512 -90)
		(property "Reference" "C536"
			(at -17.625822 -32.187134 90)
			(unlocked yes)
			(layer "F.SilkS")
			(effects
				(font
					(size 0.7874 0.5842)
					(thickness 0.1524)
				)
				(justify left)
			)
		)
		(property "Value" ""
			(at 0 0 270)
			(layer "F.Fab")
			(effects
				(font
					(size 1.27 1.27)
				)
			)
		)
		(duplicate_pad_numbers_are_jumpers no)
		(fp_line
			(start -0.7874 0.4064)
			(end -0.7874 -0.4064)
			(stroke
				(width 0.1524)
				(type default)
			)
			(layer "F.SilkS")
		)
		(fp_line
			(start 0.7874 0.4064)
			(end -0.7874 0.4064)
			(stroke
				(width 0.1524)
				(type default)
			)
			(layer "F.SilkS")
		)
		(fp_line
			(start 0 0.381)
			(end 0 -0.381)
			(stroke
				(width 0.1524)
				(type default)
			)
			(layer "F.SilkS")
		)
		(fp_line
			(start -0.7874 -0.4064)
			(end 0.7874 -0.4064)
			(stroke
				(width 0.1524)
				(type default)
			)
			(layer "F.SilkS")
		)
		(fp_line
			(start 0.7874 -0.4064)
			(end 0.7874 0.4064)
			(stroke
				(width 0.1524)
				(type default)
			)
			(layer "F.SilkS")
		)
		(fp_poly
			(pts
				(xy -0.5334 0.254) (xy -0.635 0.254) (xy -0.635 0.2286) (xy -0.635 -0.254) (xy -0.5334 -0.254) (xy -0.5334 -0.2794)
				(xy 0.5334 -0.2794) (xy 0.5334 -0.254) (xy 0.635 -0.254) (xy 0.635 0.254) (xy 0.5334 0.254) (xy 0.5334 0.2794)
				(xy -0.508 0.2794) (xy -0.5334 0.2794)
			)
			(stroke
				(width 0)
				(type default)
			)
			(fill no)
			(layer "F.CrtYd")
		)
		(pad "1" smd rect
			(at 0.40005 0 270)
			(size 0.4572 0.508)
			(layers "F.Cu" "F.Mask" "F.Paste")
			(net "P5V_NODE1")
		)
		(pad "2" smd rect
			(at -0.40005 0 270)
			(size 0.4572 0.508)
			(layers "F.Cu" "F.Mask" "F.Paste")
			(net "GND")
		)
	)
	(footprint ""
		(layer "F.Cu")
		(at 130.429 -56.652922 90)
		(property "Reference" "C539"
			(at -0.518922 1.19507 90)
			(unlocked yes)
			(layer "F.SilkS")
			(effects
				(font
					(size 0.7874 0.5842)
					(thickness 0.1524)
				)
				(justify left)
			)
		)
		(property "Value" ""
			(at 0 0 90)
			(layer "F.Fab")
			(effects
				(font
					(size 1.27 1.27)
				)
			)
		)
		(duplicate_pad_numbers_are_jumpers no)
		(fp_line
			(start 0.7874 -0.4064)
			(end 0.7874 0.4064)
			(stroke
				(width 0.1524)
				(type default)
			)
			(layer "F.SilkS")
		)
		(fp_line
			(start -0.7874 -0.4064)
			(end 0.7874 -0.4064)
			(stroke
				(width 0.1524)
				(type default)
			)
			(layer "F.SilkS")
		)
		(fp_line
			(start 0 0.381)
			(end 0 -0.381)
			(stroke
				(width 0.1524)
				(type default)
			)
			(layer "F.SilkS")
		)
		(fp_line
			(start 0.7874 0.4064)
			(end -0.7874 0.4064)
			(stroke
				(width 0.1524)
				(type default)
			)
			(layer "F.SilkS")
		)
		(fp_line
			(start -0.7874 0.4064)
			(end -0.7874 -0.4064)
			(stroke
				(width 0.1524)
				(type default)
			)
			(layer "F.SilkS")
		)
		(fp_poly
			(pts
				(xy -0.5334 0.254) (xy -0.635 0.254) (xy -0.635 0.2286) (xy -0.635 -0.254) (xy -0.5334 -0.254) (xy -0.5334 -0.2794)
				(xy 0.5334 -0.2794) (xy 0.5334 -0.254) (xy 0.635 -0.254) (xy 0.635 0.254) (xy 0.5334 0.254) (xy 0.5334 0.2794)
				(xy -0.508 0.2794) (xy -0.5334 0.2794)
			)
			(stroke
				(width 0)
				(type default)
			)
			(fill no)
			(layer "F.CrtYd")
		)
		(pad "1" smd rect
			(at 0.40005 0 90)
			(size 0.4572 0.508)
			(layers "F.Cu" "F.Mask" "F.Paste")
			(net "P3V3_NODE1")
		)
		(pad "2" smd rect
			(at -0.40005 0 90)
			(size 0.4572 0.508)
			(layers "F.Cu" "F.Mask" "F.Paste")
			(net "GND")
		)
	)
	(footprint ""
		(layer "F.Cu")
		(at 81.95056 -80.683608 -90)
		(property "Reference" "C89"
			(at 17.592294 -1.189482 90)
			(unlocked yes)
			(layer "F.SilkS")
			(effects
				(font
					(size 0.7874 0.5842)
					(thickness 0.1524)
				)
				(justify left)
			)
		)
		(property "Value" ""
			(at 0 0 270)
			(layer "F.Fab")
			(effects
				(font
					(size 1.27 1.27)
				)
			)
		)
		(duplicate_pad_numbers_are_jumpers no)
		(fp_line
			(start -0.7874 0.4064)
			(end -0.7874 -0.4064)
			(stroke
				(width 0.1524)
				(type default)
			)
			(layer "F.SilkS")
		)
		(fp_line
			(start 0.7874 0.4064)
			(end -0.7874 0.4064)
			(stroke
				(width 0.1524)
				(type default)
			)
			(layer "F.SilkS")
		)
		(fp_line
			(start 0 0.381)
			(end 0 -0.381)
			(stroke
				(width 0.1524)
				(type default)
			)
			(layer "F.SilkS")
		)
		(fp_line
			(start -0.7874 -0.4064)
			(end 0.7874 -0.4064)
			(stroke
				(width 0.1524)
				(type default)
			)
			(layer "F.SilkS")
		)
		(fp_line
			(start 0.7874 -0.4064)
			(end 0.7874 0.4064)
			(stroke
				(width 0.1524)
				(type default)
			)
			(layer "F.SilkS")
		)
		(fp_poly
			(pts
				(xy -0.5334 0.254) (xy -0.635 0.254) (xy -0.635 0.2286) (xy -0.635 -0.254) (xy -0.5334 -0.254) (xy -0.5334 -0.2794)
				(xy 0.5334 -0.2794) (xy 0.5334 -0.254) (xy 0.635 -0.254) (xy 0.635 0.254) (xy 0.5334 0.254) (xy 0.5334 0.2794)
				(xy -0.508 0.2794) (xy -0.5334 0.2794)
			)
			(stroke
				(width 0)
				(type default)
			)
			(fill no)
			(layer "F.CrtYd")
		)
		(pad "1" smd rect
			(at 0.40005 0 270)
			(size 0.4572 0.508)
			(layers "F.Cu" "F.Mask" "F.Paste")
			(net "PV_VCCP_NODE1")
		)
		(pad "2" smd rect
			(at -0.40005 0 270)
			(size 0.4572 0.508)
			(layers "F.Cu" "F.Mask" "F.Paste")
			(net "GND")
		)
	)
	(footprint ""
		(layer "F.Cu")
		(at 92.6084 -3.993134 180)
		(property "Reference" "R179"
			(at 1.88722 -1.2954 0)
			(unlocked yes)
			(layer "F.SilkS")
			(effects
				(font
					(size 0.7874 0.5842)
					(thickness 0.1524)
				)
				(justify left)
			)
		)
		(property "Value" ""
			(at 0 0 180)
			(layer "F.Fab")
			(effects
				(font
					(size 1.27 1.27)
				)
			)
		)
		(duplicate_pad_numbers_are_jumpers no)
		(fp_line
			(start 0.7874 0.4064)
			(end -0.7874 0.4064)
			(stroke
				(width 0.1524)
				(type default)
			)
			(layer "F.SilkS")
		)
		(fp_line
			(start 0.7874 -0.4064)
			(end 0.7874 0.4064)
			(stroke
				(width 0.1524)
				(type default)
			)
			(layer "F.SilkS")
		)
		(fp_line
			(start -0.7874 0.4064)
			(end -0.7874 -0.4064)
			(stroke
				(width 0.1524)
				(type default)
			)
			(layer "F.SilkS")
		)
		(fp_line
			(start -0.7874 -0.4064)
			(end 0.7874 -0.4064)
			(stroke
				(width 0.1524)
				(type default)
			)
			(layer "F.SilkS")
		)
		(fp_poly
			(pts
				(xy -0.508 0.2794) (xy -0.508 0.2286) (xy -0.635 0.2286) (xy -0.635 -0.254) (xy -0.5334 -0.254)
				(xy -0.5334 -0.2794) (xy 0.5334 -0.2794) (xy 0.5334 -0.254) (xy 0.635 -0.254) (xy 0.635 0.254) (xy 0.5334 0.254)
				(xy 0.5334 0.2794)
			)
			(stroke
				(width 0)
				(type default)
			)
			(fill no)
			(layer "F.CrtYd")
		)
		(pad "1" smd rect
			(at 0.40005 0 180)
			(size 0.4572 0.508)
			(layers "F.Cu" "F.Mask" "F.Paste")
			(net "IRQ_CPU_NODE1_SERIAL")
		)
		(pad "2" smd rect
			(at -0.40005 0 180)
			(size 0.4572 0.508)
			(layers "F.Cu" "F.Mask" "F.Paste")
			(net "TPM_LPC_SERIRQ_PORT80_NODE1")
		)
	)
	(footprint ""
		(layer "F.Cu")
		(at 164.271198 -161.395918 90)
		(property "Reference" "R580"
			(at -8.091678 17.572736 90)
			(unlocked yes)
			(layer "F.SilkS")
			(effects
				(font
					(size 0.7874 0.5842)
					(thickness 0.1524)
				)
				(justify left)
			)
		)
		(property "Value" ""
			(at 0 0 90)
			(layer "F.Fab")
			(effects
				(font
					(size 1.27 1.27)
				)
			)
		)
		(duplicate_pad_numbers_are_jumpers no)
		(fp_line
			(start 0.7874 -0.4064)
			(end 0.7874 0.4064)
			(stroke
				(width 0.1524)
				(type default)
			)
			(layer "F.SilkS")
		)
		(fp_line
			(start -0.7874 -0.4064)
			(end 0.7874 -0.4064)
			(stroke
				(width 0.1524)
				(type default)
			)
			(layer "F.SilkS")
		)
		(fp_line
			(start 0.7874 0.4064)
			(end -0.7874 0.4064)
			(stroke
				(width 0.1524)
				(type default)
			)
			(layer "F.SilkS")
		)
		(fp_line
			(start -0.7874 0.4064)
			(end -0.7874 -0.4064)
			(stroke
				(width 0.1524)
				(type default)
			)
			(layer "F.SilkS")
		)
		(fp_poly
			(pts
				(xy -0.508 0.2794) (xy -0.508 0.2286) (xy -0.635 0.2286) (xy -0.635 -0.254) (xy -0.5334 -0.254)
				(xy -0.5334 -0.2794) (xy 0.5334 -0.2794) (xy 0.5334 -0.254) (xy 0.635 -0.254) (xy 0.635 0.254) (xy 0.5334 0.254)
				(xy 0.5334 0.2794)
			)
			(stroke
				(width 0)
				(type default)
			)
			(fill no)
			(layer "F.CrtYd")
		)
		(pad "1" smd rect
			(at 0.40005 0 90)
			(size 0.4572 0.508)
			(layers "F.Cu" "F.Mask" "F.Paste")
			(net "P3V3_NODE1")
		)
		(pad "2" smd rect
			(at -0.40005 0 90)
			(size 0.4572 0.508)
			(layers "F.Cu" "F.Mask" "F.Paste")
			(net "LAN2_NC_SI_RXD1")
		)
	)
	(footprint ""
		(layer "F.Cu")
		(at 108.721906 -140.341096 90)
		(property "Reference" "PR65"
			(at 2.647696 4.129532 90)
			(unlocked yes)
			(layer "F.SilkS")
			(effects
				(font
					(size 0.635 0.4064)
					(thickness 0.1524)
				)
				(justify left)
			)
		)
		(property "Value" ""
			(at 0 0 90)
			(layer "F.Fab")
			(effects
				(font
					(size 1.27 1.27)
				)
			)
		)
		(duplicate_pad_numbers_are_jumpers no)
		(fp_line
			(start 0.7874 -0.4064)
			(end 0.7874 0.4064)
			(stroke
				(width 0.1524)
				(type default)
			)
			(layer "F.SilkS")
		)
		(fp_line
			(start -0.7874 -0.4064)
			(end 0.7874 -0.4064)
			(stroke
				(width 0.1524)
				(type default)
			)
			(layer "F.SilkS")
		)
		(fp_line
			(start 0.7874 0.4064)
			(end -0.7874 0.4064)
			(stroke
				(width 0.1524)
				(type default)
			)
			(layer "F.SilkS")
		)
		(fp_line
			(start -0.7874 0.4064)
			(end -0.7874 -0.4064)
			(stroke
				(width 0.1524)
				(type default)
			)
			(layer "F.SilkS")
		)
		(fp_poly
			(pts
				(xy -0.508 0.2794) (xy -0.508 0.2286) (xy -0.635 0.2286) (xy -0.635 -0.254) (xy -0.5334 -0.254)
				(xy -0.5334 -0.2794) (xy 0.5334 -0.2794) (xy 0.5334 -0.254) (xy 0.635 -0.254) (xy 0.635 0.254) (xy 0.5334 0.254)
				(xy 0.5334 0.2794)
			)
			(stroke
				(width 0)
				(type default)
			)
			(fill no)
			(layer "F.CrtYd")
		)
		(pad "1" smd rect
			(at 0.40005 0 90)
			(size 0.4572 0.508)
			(layers "F.Cu" "F.Mask" "F.Paste")
			(net "AGND_PVCCP_NODE1")
		)
		(pad "2" smd rect
			(at -0.40005 0 90)
			(size 0.4572 0.508)
			(layers "F.Cu" "F.Mask" "F.Paste")
			(net "VR_PVCCP_NODE1_ICCMAX")
		)
	)
)
